FILE_TYPE = MACRO_DRAWING;
SET COLOR_WIRE YELLOW;
SET COLOR_PROP ORANGE;
SET COLOR_DOT WHITE;
SET COLOR_ARC YELLOW;
SET COLOR_BODY GREEN;
SET COLOR_NOTE PURPLE;
SET PROP_DISPLAY VALUE;
SET PAGE_NUMBER P38;
FORCEADD VCC_CORE..1
(-2375 4000);
FORCEPROP 3 LASTPIN (-2375 3950) SIG_NAME PVCCFA_EHV_FIVRA_CPU0\g
J 0
(-2365 3960);
DISPLAY 0.659574 (-2365 3960);
PAINT MONO (-2365 3960);
DISPLAY INVISIBLE (-2365 3960);
FORCEPROP 1 LAST HDL_POWER PVCCFA_EHV_FIVRA_CPU0
J 1
(-2375 4050);
DISPLAY 1.148936 (-2375 4050);
PAINT GREEN (-2375 4050);
FORCEPROP 2 LAST CDS_LIB logical_power
J 0
(-2375 4000);
PAINT MONO (-2375 4000);
DISPLAY INVISIBLE (-2375 4000);
FORCEPROP 1 LAST PATH I2
J 0
(-2325 4025);
DISPLAY 0.872340 (-2325 4025);
PAINT AQUA (-2325 4025);
DISPLAY INVISIBLE (-2325 4025);
FORCEADD SOCKET4677_AZIF0045P001C01CS..30
(-925 2050);
FORCEPROP 1 LAST PART_NUMBER DGA^7000023
J 0
(-1975 3650);
DISPLAY 0.723404 (-1975 3650);
PAINT GREEN (-1975 3650);
DISPLAY INVISIBLE (-1975 3650);
FORCEPROP 2 LAST PART_TYPE SMLF
J 0
(-1975 3825);
DISPLAY 1.021277 (-1975 3825);
FORCEPROP 1 LAST MATERIAL IO
J 0
(-1975 3575);
DISPLAY 0.723404 (-1975 3575);
PAINT GREEN (-1975 3575);
FORCEPROP 2 LAST VALUE SOCKET4677_AZIF0045-P001C01CS
J 0
(-1975 3775);
DISPLAY 1.021277 (-1975 3775);
FORCEPROP 1 LAST $LOCATION U2
J 0
(-1975 3725);
DISPLAY 0.723404 (-1975 3725);
PAINT GREEN (-1975 3725);
FORCEPROP 0 LASTPIN (275 1925) $PN AA11
J 0
(285 1935);
DISPLAY 0.680851 (285 1935);
PAINT MONO (285 1935);
FORCEPROP 0 LASTPIN (275 1975) $PN AA15
J 0
(285 1985);
DISPLAY 0.680851 (285 1985);
PAINT MONO (285 1985);
FORCEPROP 0 LASTPIN (275 1875) $PN AA7
J 0
(285 1885);
DISPLAY 0.680851 (285 1885);
PAINT MONO (285 1885);
FORCEPROP 0 LASTPIN (275 2025) $PN AD85
J 0
(285 2035);
DISPLAY 0.680851 (285 2035);
PAINT MONO (285 2035);
FORCEPROP 0 LASTPIN (275 2075) $PN AD89
J 0
(285 2085);
DISPLAY 0.680851 (285 2085);
PAINT MONO (285 2085);
FORCEPROP 0 LASTPIN (275 2175) $PN AE11
J 0
(285 2185);
DISPLAY 0.680851 (285 2185);
PAINT MONO (285 2185);
FORCEPROP 0 LASTPIN (275 2225) $PN AE15
J 0
(285 2235);
DISPLAY 0.680851 (285 2235);
PAINT MONO (285 2235);
FORCEPROP 0 LASTPIN (275 2125) $PN AE7
J 0
(285 2135);
DISPLAY 0.680851 (285 2135);
PAINT MONO (285 2135);
FORCEPROP 0 LASTPIN (275 2275) $PN AF77
J 0
(285 2285);
DISPLAY 0.680851 (285 2285);
PAINT MONO (285 2285);
FORCEPROP 0 LASTPIN (275 2325) $PN AG78
J 0
(285 2335);
DISPLAY 0.680851 (285 2335);
PAINT MONO (285 2335);
FORCEPROP 0 LASTPIN (275 2375) $PN AH85
J 0
(285 2385);
DISPLAY 0.680851 (285 2385);
PAINT MONO (285 2385);
FORCEPROP 0 LASTPIN (275 2425) $PN AH89
J 0
(285 2435);
DISPLAY 0.680851 (285 2435);
PAINT MONO (285 2435);
FORCEPROP 0 LASTPIN (275 2525) $PN AJ11
J 0
(285 2535);
DISPLAY 0.680851 (285 2535);
PAINT MONO (285 2535);
FORCEPROP 0 LASTPIN (275 2575) $PN AJ15
J 0
(285 2585);
DISPLAY 0.680851 (285 2585);
PAINT MONO (285 2585);
FORCEPROP 0 LASTPIN (275 2475) $PN AJ7
J 0
(285 2485);
DISPLAY 0.680851 (285 2485);
PAINT MONO (285 2485);
FORCEPROP 0 LASTPIN (275 2625) $PN AM79
J 0
(285 2635);
DISPLAY 0.680851 (285 2635);
PAINT MONO (285 2635);
FORCEPROP 0 LASTPIN (275 2675) $PN AM85
J 0
(285 2685);
DISPLAY 0.680851 (285 2685);
PAINT MONO (285 2685);
FORCEPROP 0 LASTPIN (275 2725) $PN AM89
J 0
(285 2735);
DISPLAY 0.680851 (285 2735);
PAINT MONO (285 2735);
FORCEPROP 0 LASTPIN (275 2825) $PN AN11
J 0
(285 2835);
DISPLAY 0.680851 (285 2835);
PAINT MONO (285 2835);
FORCEPROP 0 LASTPIN (275 2875) $PN AN15
J 0
(285 2885);
DISPLAY 0.680851 (285 2885);
PAINT MONO (285 2885);
FORCEPROP 0 LASTPIN (275 2775) $PN AN7
J 0
(285 2785);
DISPLAY 0.680851 (285 2785);
PAINT MONO (285 2785);
FORCEPROP 0 LASTPIN (275 2925) $PN AN80
J 0
(285 2935);
DISPLAY 0.680851 (285 2935);
PAINT MONO (285 2935);
FORCEPROP 0 LASTPIN (275 2975) $PN AT73
J 0
(285 2985);
DISPLAY 0.680851 (285 2985);
PAINT MONO (285 2985);
FORCEPROP 0 LASTPIN (275 3025) $PN AT89
J 0
(285 3035);
DISPLAY 0.680851 (285 3035);
PAINT MONO (285 3035);
FORCEPROP 0 LASTPIN (275 3075) $PN AU15
J 0
(285 3085);
DISPLAY 0.680851 (285 3085);
PAINT MONO (285 3085);
FORCEPROP 0 LASTPIN (275 3125) $PN AW76
J 0
(285 3135);
DISPLAY 0.680851 (285 3135);
PAINT MONO (285 3135);
FORCEPROP 0 LASTPIN (275 3175) $PN AY89
J 0
(285 3185);
DISPLAY 0.680851 (285 3185);
PAINT MONO (285 3185);
FORCEPROP 0 LASTPIN (275 3225) $PN BE72
J 0
(285 3235);
DISPLAY 0.680851 (285 3235);
PAINT MONO (285 3235);
FORCEPROP 0 LASTPIN (275 3275) $PN BF77
J 0
(285 3285);
DISPLAY 0.680851 (285 3285);
PAINT MONO (285 3285);
FORCEPROP 0 LASTPIN (275 3325) $PN BH79
J 0
(285 3335);
DISPLAY 0.680851 (285 3335);
PAINT MONO (285 3335);
FORCEPROP 0 LASTPIN (275 3375) $PN BJ72
J 0
(285 3385);
DISPLAY 0.680851 (285 3385);
PAINT MONO (285 3385);
FORCEPROP 0 LASTPIN (-2125 875) $PN BJ78
J 2
(-2135 885);
DISPLAY 0.680851 (-2135 885);
PAINT MONO (-2135 885);
FORCEPROP 0 LASTPIN (275 725) $PN C84
J 0
(285 735);
DISPLAY 0.680851 (285 735);
PAINT MONO (285 735);
FORCEPROP 0 LASTPIN (275 775) $PN C88
J 0
(285 785);
DISPLAY 0.680851 (285 785);
PAINT MONO (285 785);
FORCEPROP 0 LASTPIN (-2125 925) $PN CE74
J 2
(-2135 935);
DISPLAY 0.680851 (-2135 935);
PAINT MONO (-2135 935);
FORCEPROP 0 LASTPIN (-2125 975) $PN CK73
J 2
(-2135 985);
DISPLAY 0.680851 (-2135 985);
PAINT MONO (-2135 985);
FORCEPROP 0 LASTPIN (-2125 1025) $PN CK79
J 2
(-2135 1035);
DISPLAY 0.680851 (-2135 1035);
PAINT MONO (-2135 1035);
FORCEPROP 0 LASTPIN (-2125 1075) $PN CM73
J 2
(-2135 1085);
DISPLAY 0.680851 (-2135 1085);
PAINT MONO (-2135 1085);
FORCEPROP 0 LASTPIN (-2125 1125) $PN CN78
J 2
(-2135 1135);
DISPLAY 0.680851 (-2135 1135);
PAINT MONO (-2135 1135);
FORCEPROP 0 LASTPIN (-2125 1175) $PN CP73
J 2
(-2135 1185);
DISPLAY 0.680851 (-2135 1185);
PAINT MONO (-2135 1185);
FORCEPROP 0 LASTPIN (-2125 1225) $PN CT77
J 2
(-2135 1235);
DISPLAY 0.680851 (-2135 1235);
PAINT MONO (-2135 1235);
FORCEPROP 0 LASTPIN (-2125 1275) $PN CT85
J 2
(-2135 1285);
DISPLAY 0.680851 (-2135 1285);
PAINT MONO (-2135 1285);
FORCEPROP 0 LASTPIN (-2125 1325) $PN CY75
J 2
(-2135 1335);
DISPLAY 0.680851 (-2135 1335);
PAINT MONO (-2135 1335);
FORCEPROP 0 LASTPIN (-2125 1375) $PN CY79
J 2
(-2135 1385);
DISPLAY 0.680851 (-2135 1385);
PAINT MONO (-2135 1385);
FORCEPROP 0 LASTPIN (-2125 1425) $PN CY85
J 2
(-2135 1435);
DISPLAY 0.680851 (-2135 1435);
PAINT MONO (-2135 1435);
FORCEPROP 0 LASTPIN (-2125 1475) $PN CY89
J 2
(-2135 1485);
DISPLAY 0.680851 (-2135 1485);
PAINT MONO (-2135 1485);
FORCEPROP 0 LASTPIN (-2125 1525) $PN DD77
J 2
(-2135 1535);
DISPLAY 0.680851 (-2135 1535);
PAINT MONO (-2135 1535);
FORCEPROP 0 LASTPIN (-2125 1575) $PN DD83
J 2
(-2135 1585);
DISPLAY 0.680851 (-2135 1585);
PAINT MONO (-2135 1585);
FORCEPROP 0 LASTPIN (-2125 1625) $PN DD85
J 2
(-2135 1635);
DISPLAY 0.680851 (-2135 1635);
PAINT MONO (-2135 1635);
FORCEPROP 0 LASTPIN (-2125 1675) $PN DD89
J 2
(-2135 1685);
DISPLAY 0.680851 (-2135 1685);
PAINT MONO (-2135 1685);
FORCEPROP 0 LASTPIN (-2125 1725) $PN DH89
J 2
(-2135 1735);
DISPLAY 0.680851 (-2135 1735);
PAINT MONO (-2135 1735);
FORCEPROP 0 LASTPIN (-2125 1775) $PN DM83
J 2
(-2135 1785);
DISPLAY 0.680851 (-2135 1785);
PAINT MONO (-2135 1785);
FORCEPROP 0 LASTPIN (-2125 1825) $PN DM85
J 2
(-2135 1835);
DISPLAY 0.680851 (-2135 1835);
PAINT MONO (-2135 1835);
FORCEPROP 0 LASTPIN (-2125 1875) $PN DM89
J 2
(-2135 1885);
DISPLAY 0.680851 (-2135 1885);
PAINT MONO (-2135 1885);
FORCEPROP 0 LASTPIN (-2125 2025) $PN DN11
J 2
(-2135 2035);
DISPLAY 0.680851 (-2135 2035);
PAINT MONO (-2135 2035);
FORCEPROP 0 LASTPIN (-2125 2075) $PN DN15
J 2
(-2135 2085);
DISPLAY 0.680851 (-2135 2085);
PAINT MONO (-2135 2085);
FORCEPROP 0 LASTPIN (-2125 1925) $PN DN3
J 2
(-2135 1935);
DISPLAY 0.680851 (-2135 1935);
PAINT MONO (-2135 1935);
FORCEPROP 0 LASTPIN (-2125 1975) $PN DN7
J 2
(-2135 1985);
DISPLAY 0.680851 (-2135 1985);
PAINT MONO (-2135 1985);
FORCEPROP 0 LASTPIN (-2125 2125) $PN DT79
J 2
(-2135 2135);
DISPLAY 0.680851 (-2135 2135);
PAINT MONO (-2135 2135);
FORCEPROP 0 LASTPIN (-2125 2175) $PN DT85
J 2
(-2135 2185);
DISPLAY 0.680851 (-2135 2185);
PAINT MONO (-2135 2185);
FORCEPROP 0 LASTPIN (-2125 2225) $PN DT89
J 2
(-2135 2235);
DISPLAY 0.680851 (-2135 2235);
PAINT MONO (-2135 2235);
FORCEPROP 0 LASTPIN (-2125 2375) $PN DU11
J 2
(-2135 2385);
DISPLAY 0.680851 (-2135 2385);
PAINT MONO (-2135 2385);
FORCEPROP 0 LASTPIN (-2125 2425) $PN DU15
J 2
(-2135 2435);
DISPLAY 0.680851 (-2135 2435);
PAINT MONO (-2135 2435);
FORCEPROP 0 LASTPIN (-2125 2275) $PN DU3
J 2
(-2135 2285);
DISPLAY 0.680851 (-2135 2285);
PAINT MONO (-2135 2285);
FORCEPROP 0 LASTPIN (-2125 2325) $PN DU7
J 2
(-2135 2335);
DISPLAY 0.680851 (-2135 2335);
PAINT MONO (-2135 2335);
FORCEPROP 0 LASTPIN (-2125 2475) $PN DY85
J 2
(-2135 2485);
DISPLAY 0.680851 (-2135 2485);
PAINT MONO (-2135 2485);
FORCEPROP 0 LASTPIN (-2125 2525) $PN DY89
J 2
(-2135 2535);
DISPLAY 0.680851 (-2135 2535);
PAINT MONO (-2135 2535);
FORCEPROP 0 LASTPIN (-2125 2675) $PN EA11
J 2
(-2135 2685);
DISPLAY 0.680851 (-2135 2685);
PAINT MONO (-2135 2685);
FORCEPROP 0 LASTPIN (-2125 2725) $PN EA15
J 2
(-2135 2735);
DISPLAY 0.680851 (-2135 2735);
PAINT MONO (-2135 2735);
FORCEPROP 0 LASTPIN (-2125 2575) $PN EA3
J 2
(-2135 2585);
DISPLAY 0.680851 (-2135 2585);
PAINT MONO (-2135 2585);
FORCEPROP 0 LASTPIN (-2125 2625) $PN EA7
J 2
(-2135 2635);
DISPLAY 0.680851 (-2135 2635);
PAINT MONO (-2135 2635);
FORCEPROP 0 LASTPIN (-2125 2775) $PN EC78
J 2
(-2135 2785);
DISPLAY 0.680851 (-2135 2785);
PAINT MONO (-2135 2785);
FORCEPROP 0 LASTPIN (-2125 2825) $PN ED79
J 2
(-2135 2835);
DISPLAY 0.680851 (-2135 2835);
PAINT MONO (-2135 2835);
FORCEPROP 0 LASTPIN (-2125 2875) $PN ED85
J 2
(-2135 2885);
DISPLAY 0.680851 (-2135 2885);
PAINT MONO (-2135 2885);
FORCEPROP 0 LASTPIN (-2125 2925) $PN ED89
J 2
(-2135 2935);
DISPLAY 0.680851 (-2135 2935);
PAINT MONO (-2135 2935);
FORCEPROP 0 LASTPIN (-2125 3025) $PN EE11
J 2
(-2135 3035);
DISPLAY 0.680851 (-2135 3035);
PAINT MONO (-2135 3035);
FORCEPROP 0 LASTPIN (-2125 3075) $PN EE15
J 2
(-2135 3085);
DISPLAY 0.680851 (-2135 3085);
PAINT MONO (-2135 3085);
FORCEPROP 0 LASTPIN (-2125 2975) $PN EE7
J 2
(-2135 2985);
DISPLAY 0.680851 (-2135 2985);
PAINT MONO (-2135 2985);
FORCEPROP 0 LASTPIN (-2125 3125) $PN EE84
J 2
(-2135 3135);
DISPLAY 0.680851 (-2135 3135);
PAINT MONO (-2135 3135);
FORCEPROP 0 LASTPIN (-2125 3175) $PN EF79
J 2
(-2135 3185);
DISPLAY 0.680851 (-2135 3185);
PAINT MONO (-2135 3185);
FORCEPROP 0 LASTPIN (-2125 3225) $PN EG80
J 2
(-2135 3235);
DISPLAY 0.680851 (-2135 3235);
PAINT MONO (-2135 3235);
FORCEPROP 0 LASTPIN (-2125 3275) $PN EJ15
J 2
(-2135 3285);
DISPLAY 0.680851 (-2135 3285);
PAINT MONO (-2135 3285);
FORCEPROP 0 LASTPIN (-2125 3325) $PN EJ84
J 2
(-2135 3335);
DISPLAY 0.680851 (-2135 3335);
PAINT MONO (-2135 3335);
FORCEPROP 0 LASTPIN (-2125 3375) $PN EN84
J 2
(-2135 3385);
DISPLAY 0.680851 (-2135 3385);
PAINT MONO (-2135 3385);
FORCEPROP 0 LASTPIN (275 825) $PN H89
J 0
(285 835);
DISPLAY 0.680851 (285 835);
PAINT MONO (285 835);
FORCEPROP 0 LASTPIN (275 925) $PN J11
J 0
(285 935);
DISPLAY 0.680851 (285 935);
PAINT MONO (285 935);
FORCEPROP 0 LASTPIN (275 875) $PN J7
J 0
(285 885);
DISPLAY 0.680851 (285 885);
PAINT MONO (285 885);
FORCEPROP 0 LASTPIN (275 975) $PN J80
J 0
(285 985);
DISPLAY 0.680851 (285 985);
PAINT MONO (285 985);
FORCEPROP 0 LASTPIN (275 1025) $PN K87
J 0
(285 1035);
DISPLAY 0.680851 (285 1035);
PAINT MONO (285 1035);
FORCEPROP 0 LASTPIN (275 1075) $PN L84
J 0
(285 1085);
DISPLAY 0.680851 (285 1085);
PAINT MONO (285 1085);
FORCEPROP 0 LASTPIN (275 1125) $PN M85
J 0
(285 1135);
DISPLAY 0.680851 (285 1135);
PAINT MONO (285 1135);
FORCEPROP 0 LASTPIN (275 1175) $PN M89
J 0
(285 1185);
DISPLAY 0.680851 (285 1185);
PAINT MONO (285 1185);
FORCEPROP 0 LASTPIN (275 1275) $PN N11
J 0
(285 1285);
DISPLAY 0.680851 (285 1285);
PAINT MONO (285 1285);
FORCEPROP 0 LASTPIN (275 1225) $PN N7
J 0
(285 1235);
DISPLAY 0.680851 (285 1235);
PAINT MONO (285 1235);
FORCEPROP 0 LASTPIN (275 1325) $PN P79
J 0
(285 1335);
DISPLAY 0.680851 (285 1335);
PAINT MONO (285 1335);
FORCEPROP 0 LASTPIN (275 1375) $PN R80
J 0
(285 1385);
DISPLAY 0.680851 (285 1385);
PAINT MONO (285 1385);
FORCEPROP 0 LASTPIN (275 1425) $PN T85
J 0
(285 1435);
DISPLAY 0.680851 (285 1435);
PAINT MONO (285 1435);
FORCEPROP 0 LASTPIN (275 1475) $PN T89
J 0
(285 1485);
DISPLAY 0.680851 (285 1485);
PAINT MONO (285 1485);
FORCEPROP 0 LASTPIN (275 1575) $PN U11
J 0
(285 1585);
DISPLAY 0.680851 (285 1585);
PAINT MONO (285 1585);
FORCEPROP 0 LASTPIN (275 1625) $PN U15
J 0
(285 1635);
DISPLAY 0.680851 (285 1635);
PAINT MONO (285 1635);
FORCEPROP 0 LASTPIN (275 1525) $PN U7
J 0
(285 1535);
DISPLAY 0.680851 (285 1535);
PAINT MONO (285 1535);
FORCEPROP 0 LASTPIN (275 1675) $PN W80
J 0
(285 1685);
DISPLAY 0.680851 (285 1685);
PAINT MONO (285 1685);
FORCEPROP 0 LASTPIN (275 1725) $PN Y79
J 0
(285 1735);
DISPLAY 0.680851 (285 1735);
PAINT MONO (285 1735);
FORCEPROP 0 LASTPIN (275 1775) $PN Y85
J 0
(285 1785);
DISPLAY 0.680851 (285 1785);
PAINT MONO (285 1785);
FORCEPROP 0 LASTPIN (275 1825) $PN Y89
J 0
(285 1835);
DISPLAY 0.680851 (285 1835);
PAINT MONO (285 1835);
FORCEPROP 2 LAST CDS_LIB pure_quanta
J 0
(-925 2050);
DISPLAY INVISIBLE (-925 2050);
FORCEPROP 1 LAST NEEDS_NO_SIZE TRUE
J 0
(-925 2050);
DISPLAY 0.723404 (-925 2050);
PAINT GREEN (-925 2050);
DISPLAY INVISIBLE (-925 2050);
FORCEPROP 1 LAST CDS_LMAN_SYM_OUTLINE -1050,1500,1050,-1450
J 0
(-925 2050);
DISPLAY 0.468085 (-925 2050);
PAINT GREEN (-925 2050);
DISPLAY INVISIBLE (-925 2050);
FORCEPROP 2 LAST CDS_LOCATION U2
J 0
(-1975 3875);
DISPLAY 1.021277 (-1975 3875);
DISPLAY INVISIBLE (-1975 3875);
FORCEPROP 0 LAST $SEC 30
J 0
(-1975 3875);
DISPLAY 0.680851 (-1975 3875);
PAINT MONO (-1975 3875);
DISPLAY INVISIBLE (-1975 3875);
FORCEPROP 2 LAST CDS_SEC 30
J 0
(-1975 3875);
DISPLAY 1.021277 (-1975 3875);
DISPLAY INVISIBLE (-1975 3875);
FORCEPROP 1 LAST PATH I4
J 0
(-925 2050);
DISPLAY 0.723404 (-925 2050);
PAINT GREEN (-925 2050);
DISPLAY INVISIBLE (-925 2050);
FORCEADD VCC_CORE..1
(525 4000);
FORCEPROP 3 LASTPIN (525 3950) SIG_NAME PVCCFA_EHV_FIVRA_CPU0\g
J 0
(535 3960);
DISPLAY 0.659574 (535 3960);
PAINT MONO (535 3960);
DISPLAY INVISIBLE (535 3960);
FORCEPROP 1 LAST HDL_POWER PVCCFA_EHV_FIVRA_CPU0
J 1
(525 4050);
DISPLAY 1.148936 (525 4050);
PAINT GREEN (525 4050);
FORCEPROP 2 LAST CDS_LIB logical_power
J 0
(525 4000);
PAINT MONO (525 4000);
DISPLAY INVISIBLE (525 4000);
FORCEPROP 1 LAST PATH I5
J 0
(575 4025);
DISPLAY 0.872340 (575 4025);
PAINT AQUA (575 4025);
DISPLAY INVISIBLE (575 4025);
FORCEADD QUANTA_TITLE_BLOCK_C..1
(3800 -1500);
FORCEPROP 0 LAST CDS_CON_LAST_MODIFIED Fri Aug 25 14:00:21 2023
J 0
(1915 -1485);
PAINT MONO (1915 -1485);
DISPLAY INVISIBLE (1915 -1485);
FORCEPROP 2 LAST CUSTOM_TXT_CDS <XR_PAGE_TITLE>
J 0
(-4090 3750);
DISPLAY 0.638298 (-4090 3750);
PAINT PINK (-4090 3750);
DISPLAY INVISIBLE (-4090 3750);
FORCEPROP 2 LAST CUSTOM_TXT_CDS <CON_PAGE_NUM> OF <CON_TOTAL_PAGES>
J 0
(3350 -1475);
DISPLAY 0.978723 (3350 -1475);
FORCEPROP 2 LAST CUSTOM_TXT_CDS <Q_NUMBER>
J 0
(2397 -1397);
DISPLAY 1.212766 (2397 -1397);
FORCEPROP 2 LAST CUSTOM_TXT_CDS <CON_LAST_MODIFIED>
J 0
(1950 -1475);
DISPLAY 0.978723 (1950 -1475);
FORCEPROP 2 LAST CUSTOM_TXT_CDS <Q_REV>
J 0
(3616 -1397);
DISPLAY 1.212766 (3616 -1397);
FORCEPROP 2 LAST CUSTOM_TXT_CDS <Q_PROJ>
J 0
(1418 -1398);
DISPLAY 1.212766 (1418 -1398);
FORCEPROP 1 LAST CUSTOM_TXT_CDS <NAME_2>
J 0
(625 -1450);
FORCEPROP 1 LAST CUSTOM_TXT_CDS <NAME_1>
J 0
(625 -1325);
FORCEPROP 1 LAST Q_TITLE SPR CPU0 POWER - VCCFA EHV FIVRA (26)
J 0
(-5566 -1474);
DISPLAY 1.957447 (-5566 -1474);
PAINT GREEN (-5566 -1474);
FORCEPROP 1 LAST Q_DEPT 
J 1
(37 -1451);
DISPLAY 1.957447 (37 -1451);
PAINT GREEN (37 -1451);
FORCEPROP 2 LAST PAGE_BORDER TRUE
J 0
(-4090 3750);
DISPLAY 0.638298 (-4090 3750);
PAINT PINK (-4090 3750);
DISPLAY INVISIBLE (-4090 3750);
FORCEPROP 1 LAST CDS_LMAN_SYM_OUTLINE -9475,6775,100,-125
J 0
(3800 -1500);
DISPLAY 0.468085 (3800 -1500);
PAINT GREEN (3800 -1500);
DISPLAY INVISIBLE (3800 -1500);
FORCEPROP 2 LAST CDS_LIB pure_quanta
J 0
(3800 -1500);
PAINT MONO (3800 -1500);
DISPLAY INVISIBLE (3800 -1500);
FORCEPROP 2 LAST CDS_XR_PAGE_TITLE CR-38 : @S9S_MB_2U_LIB.S9S_MB_2U(SCH_1):PAGE38
J 0
(-4090 3750);
DISPLAY 0.638298 (-4090 3750);
PAINT PINK (-4090 3750);
DISPLAY INVISIBLE (-4090 3750);
FORCEPROP 1 LAST COMMENT_BODY TRUE
J 0
(3812 -1513);
DISPLAY 0.978723 (3812 -1513);
PAINT GREEN (3812 -1513);
DISPLAY INVISIBLE (3812 -1513);
WIRE 16 -1 (525 3950)(525 3375);
WIRE 16 -1 (-2375 3950)(-2375 3375);
WIRE 16 -1 (-2375 875)(-2125 875);
WIRE 16 -1 (-2375 925)(-2375 875);
WIRE 16 -1 (-2375 925)(-2125 925);
WIRE 16 -1 (-2375 975)(-2375 925);
WIRE 16 -1 (-2125 975)(-2375 975);
WIRE 16 -1 (-2375 1025)(-2375 975);
WIRE 16 -1 (-2375 1025)(-2125 1025);
WIRE 16 -1 (-2375 1075)(-2375 1025);
WIRE 16 -1 (-2375 1075)(-2125 1075);
WIRE 16 -1 (-2375 1125)(-2375 1075);
WIRE 16 -1 (-2375 1125)(-2125 1125);
WIRE 16 -1 (-2375 1175)(-2375 1125);
WIRE 16 -1 (-2375 1175)(-2125 1175);
WIRE 16 -1 (-2375 1225)(-2375 1175);
WIRE 16 -1 (-2375 1225)(-2125 1225);
WIRE 16 -1 (-2375 1275)(-2375 1225);
WIRE 16 -1 (-2375 1275)(-2125 1275);
WIRE 16 -1 (-2375 1325)(-2375 1275);
WIRE 16 -1 (-2375 1325)(-2125 1325);
WIRE 16 -1 (-2375 1375)(-2375 1325);
WIRE 16 -1 (-2375 1375)(-2125 1375);
WIRE 16 -1 (-2375 1425)(-2375 1375);
WIRE 16 -1 (-2375 1425)(-2125 1425);
WIRE 16 -1 (-2375 1475)(-2375 1425);
WIRE 16 -1 (-2375 1475)(-2125 1475);
WIRE 16 -1 (-2375 1525)(-2375 1475);
WIRE 16 -1 (-2375 1525)(-2125 1525);
WIRE 16 -1 (-2375 1575)(-2375 1525);
WIRE 16 -1 (-2375 1575)(-2125 1575);
WIRE 16 -1 (-2375 1625)(-2375 1575);
WIRE 16 -1 (-2375 1625)(-2125 1625);
WIRE 16 -1 (-2375 1675)(-2375 1625);
WIRE 16 -1 (-2125 1675)(-2375 1675);
WIRE 16 -1 (-2375 1725)(-2375 1675);
WIRE 16 -1 (-2375 1725)(-2125 1725);
WIRE 16 -1 (-2375 1775)(-2375 1725);
WIRE 16 -1 (-2375 1775)(-2125 1775);
WIRE 16 -1 (-2375 1825)(-2375 1775);
WIRE 16 -1 (-2375 1825)(-2125 1825);
WIRE 16 -1 (-2375 1875)(-2375 1825);
WIRE 16 -1 (-2375 1875)(-2125 1875);
WIRE 16 -1 (-2375 1925)(-2375 1875);
WIRE 16 -1 (-2375 1925)(-2125 1925);
WIRE 16 -1 (-2375 1975)(-2375 1925);
WIRE 16 -1 (-2375 1975)(-2125 1975);
WIRE 16 -1 (-2375 2025)(-2375 1975);
WIRE 16 -1 (-2375 2025)(-2125 2025);
WIRE 16 -1 (-2375 2075)(-2375 2025);
WIRE 16 -1 (-2375 2075)(-2125 2075);
WIRE 16 -1 (-2375 2125)(-2375 2075);
WIRE 16 -1 (-2375 2125)(-2125 2125);
WIRE 16 -1 (-2375 2175)(-2375 2125);
WIRE 16 -1 (-2375 2175)(-2125 2175);
WIRE 16 -1 (-2375 2225)(-2375 2175);
WIRE 16 -1 (-2375 2225)(-2125 2225);
WIRE 16 -1 (-2375 2275)(-2375 2225);
WIRE 16 -1 (-2375 2275)(-2125 2275);
WIRE 16 -1 (-2375 2325)(-2375 2275);
WIRE 16 -1 (-2375 2325)(-2125 2325);
WIRE 16 -1 (-2375 2375)(-2375 2325);
WIRE 16 -1 (-2375 2375)(-2125 2375);
WIRE 16 -1 (-2375 2425)(-2375 2375);
WIRE 16 -1 (-2375 2425)(-2125 2425);
WIRE 16 -1 (-2375 2475)(-2375 2425);
WIRE 16 -1 (-2375 2475)(-2125 2475);
WIRE 16 -1 (-2375 2525)(-2375 2475);
WIRE 16 -1 (-2375 2525)(-2125 2525);
WIRE 16 -1 (-2375 2575)(-2375 2525);
WIRE 16 -1 (-2375 2575)(-2125 2575);
WIRE 16 -1 (-2375 2625)(-2375 2575);
WIRE 16 -1 (-2375 2625)(-2125 2625);
WIRE 16 -1 (-2375 2675)(-2375 2625);
WIRE 16 -1 (-2375 2675)(-2125 2675);
WIRE 16 -1 (-2375 2725)(-2375 2675);
WIRE 16 -1 (-2125 2725)(-2375 2725);
WIRE 16 -1 (-2375 2775)(-2375 2725);
WIRE 16 -1 (-2375 2775)(-2125 2775);
WIRE 16 -1 (-2375 2825)(-2375 2775);
WIRE 16 -1 (-2375 2825)(-2125 2825);
WIRE 16 -1 (-2375 2875)(-2375 2825);
WIRE 16 -1 (-2125 2875)(-2375 2875);
WIRE 16 -1 (-2375 2925)(-2375 2875);
WIRE 16 -1 (-2375 2925)(-2125 2925);
WIRE 16 -1 (-2375 2975)(-2375 2925);
WIRE 16 -1 (-2375 2975)(-2125 2975);
WIRE 16 -1 (-2375 3025)(-2375 2975);
WIRE 16 -1 (-2125 3025)(-2375 3025);
WIRE 16 -1 (-2375 3075)(-2375 3025);
WIRE 16 -1 (-2125 3075)(-2375 3075);
WIRE 16 -1 (-2375 3125)(-2375 3075);
WIRE 16 -1 (-2125 3125)(-2375 3125);
WIRE 16 -1 (-2375 3175)(-2375 3125);
WIRE 16 -1 (-2125 3175)(-2375 3175);
WIRE 16 -1 (-2375 3225)(-2375 3175);
WIRE 16 -1 (-2125 3225)(-2375 3225);
WIRE 16 -1 (-2375 3275)(-2375 3225);
WIRE 16 -1 (-2125 3275)(-2375 3275);
WIRE 16 -1 (-2375 3325)(-2375 3275);
WIRE 16 -1 (-2125 3325)(-2375 3325);
WIRE 16 -1 (-2375 3375)(-2375 3325);
WIRE 16 -1 (-2125 3375)(-2375 3375);
WIRE 16 -1 (525 725)(275 725);
WIRE 16 -1 (525 775)(275 775);
WIRE 16 -1 (525 775)(525 725);
WIRE 16 -1 (525 825)(275 825);
WIRE 16 -1 (525 825)(525 775);
WIRE 16 -1 (275 875)(525 875);
WIRE 16 -1 (525 825)(525 875);
WIRE 16 -1 (525 925)(275 925);
WIRE 16 -1 (525 875)(525 925);
WIRE 16 -1 (525 975)(275 975);
WIRE 16 -1 (525 975)(525 925);
WIRE 16 -1 (525 1025)(525 975);
WIRE 16 -1 (525 1025)(275 1025);
WIRE 16 -1 (525 1075)(275 1075);
WIRE 16 -1 (525 1075)(525 1025);
WIRE 16 -1 (275 1125)(525 1125);
WIRE 16 -1 (525 1125)(525 1075);
WIRE 16 -1 (275 1175)(525 1175);
WIRE 16 -1 (525 1175)(525 1125);
WIRE 16 -1 (275 1225)(525 1225);
WIRE 16 -1 (525 1175)(525 1225);
WIRE 16 -1 (275 1275)(525 1275);
WIRE 16 -1 (525 1275)(525 1225);
WIRE 16 -1 (275 1325)(525 1325);
WIRE 16 -1 (525 1325)(525 1275);
WIRE 16 -1 (275 1375)(525 1375);
WIRE 16 -1 (525 1375)(525 1325);
WIRE 16 -1 (275 1425)(525 1425);
WIRE 16 -1 (525 1425)(525 1375);
WIRE 16 -1 (275 1475)(525 1475);
WIRE 16 -1 (525 1475)(525 1425);
WIRE 16 -1 (275 1525)(525 1525);
WIRE 16 -1 (525 1525)(525 1475);
WIRE 16 -1 (525 1575)(275 1575);
WIRE 16 -1 (525 1575)(525 1525);
WIRE 16 -1 (525 1625)(275 1625);
WIRE 16 -1 (525 1625)(525 1575);
WIRE 16 -1 (525 1675)(275 1675);
WIRE 16 -1 (525 1675)(525 1625);
WIRE 16 -1 (525 1725)(275 1725);
WIRE 16 -1 (525 1725)(525 1675);
WIRE 16 -1 (525 1775)(275 1775);
WIRE 16 -1 (525 1775)(525 1725);
WIRE 16 -1 (525 1825)(275 1825);
WIRE 16 -1 (525 1825)(525 1775);
WIRE 16 -1 (525 1875)(275 1875);
WIRE 16 -1 (525 1875)(525 1825);
WIRE 16 -1 (525 1925)(275 1925);
WIRE 16 -1 (525 1925)(525 1875);
WIRE 16 -1 (525 1975)(275 1975);
WIRE 16 -1 (525 1975)(525 1925);
WIRE 16 -1 (275 2025)(525 2025);
WIRE 16 -1 (525 1975)(525 2025);
WIRE 16 -1 (525 2025)(525 2075);
WIRE 16 -1 (525 2075)(275 2075);
WIRE 16 -1 (525 2125)(275 2125);
WIRE 16 -1 (525 2125)(525 2075);
WIRE 16 -1 (525 2175)(275 2175);
WIRE 16 -1 (525 2175)(525 2125);
WIRE 16 -1 (525 2225)(275 2225);
WIRE 16 -1 (525 2225)(525 2175);
WIRE 16 -1 (275 2275)(525 2275);
WIRE 16 -1 (525 2275)(525 2225);
WIRE 16 -1 (275 2325)(525 2325);
WIRE 16 -1 (525 2325)(525 2275);
WIRE 16 -1 (275 2375)(525 2375);
WIRE 16 -1 (525 2325)(525 2375);
WIRE 16 -1 (275 2425)(525 2425);
WIRE 16 -1 (525 2425)(525 2375);
WIRE 16 -1 (275 2475)(525 2475);
WIRE 16 -1 (525 2475)(525 2425);
WIRE 16 -1 (275 2525)(525 2525);
WIRE 16 -1 (525 2525)(525 2475);
WIRE 16 -1 (275 2575)(525 2575);
WIRE 16 -1 (525 2575)(525 2525);
WIRE 16 -1 (275 2625)(525 2625);
WIRE 16 -1 (525 2625)(525 2575);
WIRE 16 -1 (275 2675)(525 2675);
WIRE 16 -1 (525 2675)(525 2625);
WIRE 16 -1 (525 2725)(275 2725);
WIRE 16 -1 (525 2725)(525 2675);
WIRE 16 -1 (525 2775)(275 2775);
WIRE 16 -1 (525 2775)(525 2725);
WIRE 16 -1 (525 2825)(275 2825);
WIRE 16 -1 (525 2825)(525 2775);
WIRE 16 -1 (525 2875)(275 2875);
WIRE 16 -1 (525 2875)(525 2825);
WIRE 16 -1 (525 2925)(275 2925);
WIRE 16 -1 (525 2925)(525 2875);
WIRE 16 -1 (525 2975)(275 2975);
WIRE 16 -1 (525 2975)(525 2925);
WIRE 16 -1 (525 3025)(275 3025);
WIRE 16 -1 (525 3025)(525 2975);
WIRE 16 -1 (525 3075)(525 3025);
WIRE 16 -1 (525 3075)(275 3075);
WIRE 16 -1 (525 3125)(275 3125);
WIRE 16 -1 (525 3125)(525 3075);
WIRE 16 -1 (275 3175)(525 3175);
WIRE 16 -1 (525 3125)(525 3175);
WIRE 16 -1 (525 3225)(275 3225);
WIRE 16 -1 (525 3175)(525 3225);
WIRE 16 -1 (525 3275)(275 3275);
WIRE 16 -1 (525 3275)(525 3225);
WIRE 16 -1 (525 3325)(275 3325);
WIRE 16 -1 (525 3325)(525 3275);
WIRE 16 -1 (525 3375)(275 3375);
WIRE 16 -1 (525 3375)(525 3325);
DOT 1 (525 3375);
DOT 1 (525 3175);
DOT 1 (525 3325);
DOT 1 (525 3275);
DOT 1 (525 3225);
DOT 1 (525 3125);
DOT 1 (525 3075);
DOT 1 (525 2575);
DOT 1 (525 2325);
DOT 1 (525 3025);
DOT 1 (525 2975);
DOT 1 (525 2925);
DOT 1 (525 2875);
DOT 1 (525 2825);
DOT 1 (525 2775);
DOT 1 (525 2725);
DOT 1 (525 2675);
DOT 1 (525 2625);
DOT 1 (525 2525);
DOT 1 (525 2475);
DOT 1 (525 2425);
DOT 1 (525 2375);
DOT 1 (525 2075);
DOT 1 (525 2125);
DOT 1 (525 2175);
DOT 1 (525 2225);
DOT 1 (525 2275);
DOT 1 (525 1075);
DOT 1 (525 1125);
DOT 1 (525 1975);
DOT 1 (525 1225);
DOT 1 (525 1275);
DOT 1 (525 1325);
DOT 1 (525 1375);
DOT 1 (525 1425);
DOT 1 (525 1475);
DOT 1 (525 1525);
DOT 1 (525 1575);
DOT 1 (525 1625);
DOT 1 (525 1675);
DOT 1 (525 1725);
DOT 1 (525 1775);
DOT 1 (525 1825);
DOT 1 (525 1875);
DOT 1 (525 1175);
DOT 1 (525 1925);
DOT 1 (525 2025);
DOT 1 (525 1025);
DOT 1 (525 875);
DOT 1 (525 975);
DOT 1 (525 925);
DOT 1 (525 825);
DOT 1 (525 775);
DOT 1 (-2375 3375);
DOT 1 (-2375 3225);
DOT 1 (-2375 3275);
DOT 1 (-2375 3325);
DOT 1 (-2375 3175);
DOT 1 (-2375 3125);
DOT 1 (-2375 3075);
DOT 1 (-2375 3025);
DOT 1 (-2375 2975);
DOT 1 (-2375 2875);
DOT 1 (-2375 2925);
DOT 1 (-2375 2825);
DOT 1 (-2375 2775);
DOT 1 (-2375 2725);
DOT 1 (-2375 2625);
DOT 1 (-2375 2575);
DOT 1 (-2375 2675);
DOT 1 (-2375 2525);
DOT 1 (-2375 2475);
DOT 1 (-2375 2325);
DOT 1 (-2375 2425);
DOT 1 (-2375 2375);
DOT 1 (-2375 2275);
DOT 1 (-2375 2225);
DOT 1 (-2375 2125);
DOT 1 (-2375 2075);
DOT 1 (-2375 2175);
DOT 1 (-2375 1975);
DOT 1 (-2375 2025);
DOT 1 (-2375 1925);
DOT 1 (-2375 1875);
DOT 1 (-2375 1825);
DOT 1 (-2375 1775);
DOT 1 (-2375 1725);
DOT 1 (-2375 1675);
DOT 1 (-2375 1575);
DOT 1 (-2375 1625);
DOT 1 (-2375 1425);
DOT 1 (-2375 1525);
DOT 1 (-2375 1475);
DOT 1 (-2375 1325);
DOT 1 (-2375 1375);
DOT 1 (-2375 1225);
DOT 1 (-2375 1275);
DOT 1 (-2375 1175);
DOT 1 (-2375 1125);
DOT 1 (-2375 1075);
DOT 1 (-2375 1025);
DOT 1 (-2375 925);
DOT 1 (-2375 975);
QUIT
